(kicad_pcb
	(version 20241229)
	(generator "pcbnew")
	(generator_version "9.0")
	(general
		(thickness 1.599998)
		(legacy_teardrops no)
	)
	(paper "A4")
	(title_block
		(title "Artix - Datacenter Secure Control Module (DC-SCM)")
		(date "2024-11-06")
		(rev "1.1.3")
		(comment 9 "footprint 110 of 544 (U14), pads 401-477 of 484")
	)
	(layers
		(0 "F.Cu" signal)
		(4 "In1.Cu" signal)
		(6 "In2.Cu" signal)
		(8 "In3.Cu" signal)
		(10 "In4.Cu" signal)
		(12 "In5.Cu" signal)
		(14 "In6.Cu" signal)
		(2 "B.Cu" signal)
		(9 "F.Adhes" user "F.Adhesive")
		(11 "B.Adhes" user "B.Adhesive")
		(13 "F.Paste" user)
		(15 "B.Paste" user)
		(5 "F.SilkS" user "F.Silkscreen")
		(7 "B.SilkS" user "B.Silkscreen")
		(1 "F.Mask" user)
		(3 "B.Mask" user)
		(17 "Dwgs.User" user "User.Drawings")
		(19 "Cmts.User" user "User.Comments")
		(21 "Eco1.User" user "User.Eco1")
		(23 "Eco2.User" user "User.Eco2")
		(25 "Edge.Cuts" user)
		(27 "Margin" user)
		(31 "F.CrtYd" user "F.Courtyard")
		(29 "B.CrtYd" user "B.Courtyard")
		(35 "F.Fab" user)
		(33 "B.Fab" user)
	)
	(footprint "antmicro-footprints:BGA-484_23x23mm_Layout22x22_P1mm_FGG484"
		(layer "F.Cu")
		(at 101.275 119.675 90)
		(property "Reference" "U14"
			(at 11.965 9.405 180)
			(layer "F.SilkS")
			(effects
				(font
					(size 0.7 0.7)
					(thickness 0.15)
				)
				(justify left bottom)
			)
		)
		(property "Value" "XC7A100T-FGG484"
			(at 0 13.1 90)
			(layer "F.Fab")
			(effects
				(font
					(size 0.7 0.7)
					(thickness 0.15)
				)
				(justify left bottom)
			)
		)
		(property "Datasheet" "https://docs.xilinx.com/v/u/en-US/ds181_Artix_7_Data_Sheet"
			(at 0 0 90)
			(layer "F.Fab")
			(hide yes)
			(effects
				(font
					(size 1.27 1.27)
					(thickness 0.15)
				)
			)
		)
		(property "Description" "Artix-7 Field Programmable Gate Array IC 210 324-LFBGA, CSPBGA"
			(at 0 0 90)
			(layer "F.Fab")
			(hide yes)
			(effects
				(font
					(size 1.27 1.27)
					(thickness 0.15)
				)
			)
		)
		(property "Author" "Antmicro"
			(at 220.95 18.4 0)
			(layer "F.Fab")
			(hide yes)
			(effects
				(font
					(size 1 1)
					(thickness 0.15)
				)
			)
		)
		(property "License" "Apache-2.0"
			(at 220.95 18.4 0)
			(layer "F.Fab")
			(hide yes)
			(effects
				(font
					(size 1 1)
					(thickness 0.15)
				)
			)
		)
		(property "MPN" "XC7A100T-FGG484"
			(at 220.95 18.4 0)
			(layer "F.Fab")
			(hide yes)
			(effects
				(font
					(size 1 1)
					(thickness 0.15)
				)
			)
		)
		(property "Manufacturer" "AMD-Xilinx"
			(at 220.95 18.4 0)
			(layer "F.Fab")
			(hide yes)
			(effects
				(font
					(size 1 1)
					(thickness 0.15)
				)
			)
		)
		(sheetname "/FPGA power supply/")
		(sheetfile "fpga-power-supply.kicad_sch")
		(solder_mask_margin 0.05)
		(attr smd)
		(pad "U5" smd circle
			(at -6.5 5.499 90)
			(size 0.5 0.5)
			(layers "F.Cu" "F.Mask" "F.Paste")
			(net 94 "SGPIO_RESET_N")
			(pinfunction "IO_L14N_T2_SRCC_34")
			(pintype "bidirectional")
		)
		(pad "U6" smd circle
			(at -5.5 5.499 90)
			(size 0.5 0.5)
			(layers "F.Cu" "F.Mask" "F.Paste")
			(net 42 "I2C[10]_SCL")
			(pinfunction "IO_L16P_T2_34")
			(pintype "bidirectional")
		)
		(pad "U7" smd circle
			(at -4.5 5.499 90)
			(size 0.5 0.5)
			(layers "F.Cu" "F.Mask" "F.Paste")
			(net 95 "SGPIO_INTR_N")
			(pinfunction "IO_25_34")
			(pintype "bidirectional")
		)
		(pad "U8" smd circle
			(at -3.5 5.499 90)
			(size 0.5 0.5)
			(layers "F.Cu" "F.Mask" "F.Paste")
			(net 342 "Net-(U14D-CFGBVS_0)")
			(pinfunction "CFGBVS_0")
			(pintype "bidirectional")
		)
		(pad "U9" smd circle
			(at -2.5 5.499 90)
			(size 0.5 0.5)
			(layers "F.Cu" "F.Mask" "F.Paste")
			(net 259 "/FPGA banks 34-35 & CFG/MODE2")
			(pinfunction "M2_0")
			(pintype "bidirectional")
		)
		(pad "U10" smd circle
			(at -1.5 5.499 90)
			(size 0.5 0.5)
			(layers "F.Cu" "F.Mask" "F.Paste")
			(net 268 "/FPGA banks 34-35 & CFG/MODE1")
			(pinfunction "M1_0")
			(pintype "bidirectional")
		)
		(pad "U11" smd circle
			(at -0.5 5.499 90)
			(size 0.5 0.5)
			(layers "F.Cu" "F.Mask" "F.Paste")
			(net 267 "/FPGA banks 34-35 & CFG/MODE0")
			(pinfunction "M0_0")
			(pintype "bidirectional")
		)
		(pad "U12" smd circle
			(at 0.498 5.499 90)
			(size 0.5 0.5)
			(layers "F.Cu" "F.Mask" "F.Paste")
			(net 222 "INIT")
			(pinfunction "INIT_B_0")
			(pintype "bidirectional")
		)
		(pad "U13" smd circle
			(at 1.499 5.499 90)
			(size 0.5 0.5)
			(layers "F.Cu" "F.Mask" "F.Paste")
			(net 14 "JTAG_TDO")
			(pinfunction "TDO_0")
			(pintype "bidirectional")
		)
		(pad "U14" smd circle
			(at 2.499 5.499 90)
			(size 0.5 0.5)
			(layers "F.Cu" "F.Mask" "F.Paste")
			(net 1 "GND")
			(pinfunction "GND")
			(pintype "passive")
		)
		(pad "U15" smd circle
			(at 3.499 5.499 90)
			(size 0.5 0.5)
			(layers "F.Cu" "F.Mask" "F.Paste")
			(net 628 "unconnected-(U14A-IO_L14P_T2_SRCC_13-PadU15)")
			(pinfunction "IO_L14P_T2_SRCC_13")
			(pintype "bidirectional+no_connect")
		)
		(pad "U16" smd circle
			(at 4.498 5.499 90)
			(size 0.5 0.5)
			(layers "F.Cu" "F.Mask" "F.Paste")
			(net 629 "unconnected-(U14A-IO_L17N_T2_13-PadU16)")
			(pinfunction "IO_L17N_T2_13")
			(pintype "bidirectional+no_connect")
		)
		(pad "U17" smd circle
			(at 5.499 5.499 90)
			(size 0.5 0.5)
			(layers "F.Cu" "F.Mask" "F.Paste")
			(net 326 "MMC_DAT5")
			(pinfunction "IO_L18P_T2_A12_D28_14")
			(pintype "bidirectional")
		)
		(pad "U18" smd circle
			(at 6.499 5.499 90)
			(size 0.5 0.5)
			(layers "F.Cu" "F.Mask" "F.Paste")
			(net 325 "MMC_DAT4")
			(pinfunction "IO_L18N_T2_A11_D27_14")
			(pintype "bidirectional")
		)
		(pad "U19" smd circle
			(at 7.499 5.499 90)
			(size 0.5 0.5)
			(layers "F.Cu" "F.Mask" "F.Paste")
			(net 2 "VCC3V3")
			(pinfunction "VCCO_14")
			(pintype "passive")
		)
		(pad "U20" smd circle
			(at 8.499 5.499 90)
			(size 0.5 0.5)
			(layers "F.Cu" "F.Mask" "F.Paste")
			(net 317 "USR_LED1")
			(pinfunction "IO_L11P_T1_SRCC_14")
			(pintype "bidirectional")
		)
		(pad "U21" smd circle
			(at 9.499 5.499 90)
			(size 0.5 0.5)
			(layers "F.Cu" "F.Mask" "F.Paste")
			(net 40 "UART1_SCM_TX")
			(pinfunction "IO_L4N_T0_D05_14")
			(pintype "bidirectional")
		)
		(pad "U22" smd circle
			(at 10.499 5.499 90)
			(size 0.5 0.5)
			(layers "F.Cu" "F.Mask" "F.Paste")
			(net 260 "/FPGA banks 13-16/PUDC_B")
			(pinfunction "IO_L3P_T0_DQS_PUDC_B_14")
			(pintype "bidirectional")
		)
		(pad "V1" smd circle
			(at -10.5 6.499 90)
			(size 0.5 0.5)
			(layers "F.Cu" "F.Mask" "F.Paste")
			(net 1 "GND")
			(pinfunction "GND")
			(pintype "passive")
		)
		(pad "V2" smd circle
			(at -9.5 6.499 90)
			(size 0.5 0.5)
			(layers "F.Cu" "F.Mask" "F.Paste")
			(net 391 "DBP_PREQ_N_R")
			(pinfunction "IO_L2N_T0_34")
			(pintype "bidirectional")
		)
		(pad "V3" smd circle
			(at -8.5 6.499 90)
			(size 0.5 0.5)
			(layers "F.Cu" "F.Mask" "F.Paste")
			(net 390 "SYS_PWROK_R")
			(pinfunction "IO_L6N_T0_VREF_34")
			(pintype "bidirectional")
		)
		(pad "V4" smd circle
			(at -7.5 6.499 90)
			(size 0.5 0.5)
			(layers "F.Cu" "F.Mask" "F.Paste")
			(net 461 "ULPI2_CLKOUT")
			(pinfunction "IO_L12P_T1_MRCC_34")
			(pintype "bidirectional")
		)
		(pad "V5" smd circle
			(at -6.5 6.499 90)
			(size 0.5 0.5)
			(layers "F.Cu" "F.Mask" "F.Paste")
			(net 86 "SGPIO0_DO")
			(pinfunction "IO_L16N_T2_34")
			(pintype "bidirectional")
		)
		(pad "V6" smd circle
			(at -5.5 6.499 90)
			(size 0.5 0.5)
			(layers "F.Cu" "F.Mask" "F.Paste")
			(net 2 "VCC3V3")
			(pinfunction "VCCO_34")
			(pintype "passive")
		)
		(pad "V7" smd circle
			(at -4.5 6.499 90)
			(size 0.5 0.5)
			(layers "F.Cu" "F.Mask" "F.Paste")
			(net 89 "SGPIO0_LD")
			(pinfunction "IO_L19P_T3_34")
			(pintype "bidirectional")
		)
		(pad "V8" smd circle
			(at -3.5 6.499 90)
			(size 0.5 0.5)
			(layers "F.Cu" "F.Mask" "F.Paste")
			(net 44 "I2C[12]_SCL")
			(pinfunction "IO_L21N_T3_DQS_34")
			(pintype "bidirectional")
		)
		(pad "V9" smd circle
			(at -2.5 6.499 90)
			(size 0.5 0.5)
			(layers "F.Cu" "F.Mask" "F.Paste")
			(net 43 "I2C[12]_SDA")
			(pinfunction "IO_L21P_T3_DQS_34")
			(pintype "bidirectional")
		)
		(pad "V10" smd circle
			(at -1.5 6.499 90)
			(size 0.5 0.5)
			(layers "F.Cu" "F.Mask" "F.Paste")
			(net 630 "unconnected-(U14A-IO_L10P_T1_13-PadV10)")
			(pinfunction "IO_L10P_T1_13")
			(pintype "bidirectional+no_connect")
		)
		(pad "V11" smd circle
			(at -0.5 6.499 90)
			(size 0.5 0.5)
			(layers "F.Cu" "F.Mask" "F.Paste")
			(net 1 "GND")
			(pinfunction "GND")
			(pintype "passive")
		)
		(pad "V12" smd circle
			(at 0.498 6.499 90)
			(size 0.5 0.5)
			(layers "F.Cu" "F.Mask" "F.Paste")
			(net 15 "JTAG_TCK")
			(pinfunction "TCK_0")
			(pintype "bidirectional")
		)
		(pad "V13" smd circle
			(at 1.499 6.499 90)
			(size 0.5 0.5)
			(layers "F.Cu" "F.Mask" "F.Paste")
			(net 631 "unconnected-(U14A-IO_L13P_T2_MRCC_13-PadV13)")
			(pinfunction "IO_L13P_T2_MRCC_13")
			(pintype "bidirectional+no_connect")
		)
		(pad "V14" smd circle
			(at 2.499 6.499 90)
			(size 0.5 0.5)
			(layers "F.Cu" "F.Mask" "F.Paste")
			(net 632 "unconnected-(U14A-IO_L13N_T2_MRCC_13-PadV14)")
			(pinfunction "IO_L13N_T2_MRCC_13")
			(pintype "bidirectional+no_connect")
		)
		(pad "V15" smd circle
			(at 3.499 6.499 90)
			(size 0.5 0.5)
			(layers "F.Cu" "F.Mask" "F.Paste")
			(net 633 "unconnected-(U14A-IO_L14N_T2_SRCC_13-PadV15)")
			(pinfunction "IO_L14N_T2_SRCC_13")
			(pintype "bidirectional+no_connect")
		)
		(pad "V16" smd circle
			(at 4.498 6.499 90)
			(size 0.5 0.5)
			(layers "F.Cu" "F.Mask" "F.Paste")
			(net 2 "VCC3V3")
			(pinfunction "VCCO_13")
			(pintype "passive")
		)
		(pad "V17" smd circle
			(at 5.499 6.499 90)
			(size 0.5 0.5)
			(layers "F.Cu" "F.Mask" "F.Paste")
			(net 585 "HPM_STBY_EN_R")
			(pinfunction "IO_L16P_T2_CSI_B_14")
			(pintype "bidirectional")
		)
		(pad "V18" smd circle
			(at 6.499 6.499 90)
			(size 0.5 0.5)
			(layers "F.Cu" "F.Mask" "F.Paste")
			(net 324 "MMC_DAT3")
			(pinfunction "IO_L14P_T2_SRCC_14")
			(pintype "bidirectional")
		)
		(pad "V19" smd circle
			(at 7.499 6.499 90)
			(size 0.5 0.5)
			(layers "F.Cu" "F.Mask" "F.Paste")
			(net 331 "MMC_RSTN")
			(pinfunction "IO_L14N_T2_SRCC_14")
			(pintype "bidirectional")
		)
		(pad "V20" smd circle
			(at 8.499 6.499 90)
			(size 0.5 0.5)
			(layers "F.Cu" "F.Mask" "F.Paste")
			(net 442 "ULPI1_RESET")
			(pinfunction "IO_L11N_T1_SRCC_14")
			(pintype "bidirectional")
		)
		(pad "V21" smd circle
			(at 9.499 6.499 90)
			(size 0.5 0.5)
			(layers "F.Cu" "F.Mask" "F.Paste")
			(net 1 "GND")
			(pinfunction "GND")
			(pintype "passive")
		)
		(pad "V22" smd circle
			(at 10.499 6.499 90)
			(size 0.5 0.5)
			(layers "F.Cu" "F.Mask" "F.Paste")
			(net 591 "TPM_RST")
			(pinfunction "IO_L3N_T0_DQS_EMCCLK_14")
			(pintype "bidirectional")
		)
		(pad "W1" smd circle
			(at -10.5 7.499 90)
			(size 0.5 0.5)
			(layers "F.Cu" "F.Mask" "F.Paste")
			(net 393 "RST_PLTRST_BUF_N_R")
			(pinfunction "IO_L5P_T0_34")
			(pintype "bidirectional")
		)
		(pad "W2" smd circle
			(at -9.5 7.499 90)
			(size 0.5 0.5)
			(layers "F.Cu" "F.Mask" "F.Paste")
			(net 392 "DBP_PRDY_N_R")
			(pinfunction "IO_L4P_T0_34")
			(pintype "bidirectional")
		)
		(pad "W3" smd circle
			(at -8.5 7.499 90)
			(size 0.5 0.5)
			(layers "F.Cu" "F.Mask" "F.Paste")
			(net 2 "VCC3V3")
			(pinfunction "VCCO_34")
			(pintype "power_in")
		)
		(pad "W4" smd circle
			(at -7.5 7.499 90)
			(size 0.5 0.5)
			(layers "F.Cu" "F.Mask" "F.Paste")
			(net 88 "SGPIO0_DI")
			(pinfunction "IO_L12N_T1_MRCC_34")
			(pintype "bidirectional")
		)
		(pad "W5" smd circle
			(at -6.5 7.499 90)
			(size 0.5 0.5)
			(layers "F.Cu" "F.Mask" "F.Paste")
			(net 87 "SGPIO0_CLK")
			(pinfunction "IO_L15N_T2_DQS_34")
			(pintype "bidirectional")
		)
		(pad "W6" smd circle
			(at -5.5 7.499 90)
			(size 0.5 0.5)
			(layers "F.Cu" "F.Mask" "F.Paste")
			(net 41 "I2C[10]_SDA")
			(pinfunction "IO_L15P_T2_DQS_34")
			(pintype "bidirectional")
		)
		(pad "W7" smd circle
			(at -4.5 7.499 90)
			(size 0.5 0.5)
			(layers "F.Cu" "F.Mask" "F.Paste")
			(net 34 "I2C[11]_SCL")
			(pinfunction "IO_L19N_T3_VREF_34")
			(pintype "bidirectional")
		)
		(pad "W8" smd circle
			(at -3.5 7.499 90)
			(size 0.5 0.5)
			(layers "F.Cu" "F.Mask" "F.Paste")
			(net 1 "GND")
			(pinfunction "GND")
			(pintype "passive")
		)
		(pad "W9" smd circle
			(at -2.5 7.499 90)
			(size 0.5 0.5)
			(layers "F.Cu" "F.Mask" "F.Paste")
			(net 36 "I2C[11]_SDA")
			(pinfunction "IO_L24P_T3_34")
			(pintype "bidirectional")
		)
		(pad "W10" smd circle
			(at -1.5 7.499 90)
			(size 0.5 0.5)
			(layers "F.Cu" "F.Mask" "F.Paste")
			(net 634 "unconnected-(U14A-IO_L10N_T1_13-PadW10)")
			(pinfunction "IO_L10N_T1_13")
			(pintype "bidirectional+no_connect")
		)
		(pad "W11" smd circle
			(at -0.5 7.499 90)
			(size 0.5 0.5)
			(layers "F.Cu" "F.Mask" "F.Paste")
			(net 635 "unconnected-(U14A-IO_L12P_T1_MRCC_13-PadW11)")
			(pinfunction "IO_L12P_T1_MRCC_13")
			(pintype "bidirectional+no_connect")
		)
		(pad "W12" smd circle
			(at 0.498 7.499 90)
			(size 0.5 0.5)
			(layers "F.Cu" "F.Mask" "F.Paste")
			(net 636 "unconnected-(U14A-IO_L12N_T1_MRCC_13-PadW12)")
			(pinfunction "IO_L12N_T1_MRCC_13")
			(pintype "bidirectional+no_connect")
		)
		(pad "W13" smd circle
			(at 1.499 7.499 90)
			(size 0.5 0.5)
			(layers "F.Cu" "F.Mask" "F.Paste")
			(net 2 "VCC3V3")
			(pinfunction "VCCO_13")
			(pintype "passive")
		)
		(pad "W14" smd circle
			(at 2.499 7.499 90)
			(size 0.5 0.5)
			(layers "F.Cu" "F.Mask" "F.Paste")
			(net 637 "unconnected-(U14A-IO_L6P_T0_13-PadW14)")
			(pinfunction "IO_L6P_T0_13")
			(pintype "bidirectional+no_connect")
		)
		(pad "W15" smd circle
			(at 3.499 7.499 90)
			(size 0.5 0.5)
			(layers "F.Cu" "F.Mask" "F.Paste")
			(net 638 "unconnected-(U14A-IO_L16P_T2_13-PadW15)")
			(pinfunction "IO_L16P_T2_13")
			(pintype "bidirectional+no_connect")
		)
		(pad "W16" smd circle
			(at 4.498 7.499 90)
			(size 0.5 0.5)
			(layers "F.Cu" "F.Mask" "F.Paste")
			(net 639 "unconnected-(U14A-IO_L16N_T2_13-PadW16)")
			(pinfunction "IO_L16N_T2_13")
			(pintype "bidirectional+no_connect")
		)
		(pad "W17" smd circle
			(at 5.499 7.499 90)
			(size 0.5 0.5)
			(layers "F.Cu" "F.Mask" "F.Paste")
			(net 322 "MMC_DAT1")
			(pinfunction "IO_L16N_T2_A15_D31_14")
			(pintype "bidirectional")
		)
		(pad "W18" smd circle
			(at 6.499 7.499 90)
			(size 0.5 0.5)
			(layers "F.Cu" "F.Mask" "F.Paste")
			(net 1 "GND")
			(pinfunction "GND")
			(pintype "passive")
		)
		(pad "W19" smd circle
			(at 7.499 7.499 90)
			(size 0.5 0.5)
			(layers "F.Cu" "F.Mask" "F.Paste")
			(net 447 "ULPI1_CLKOUT")
			(pinfunction "IO_L12P_T1_MRCC_14")
			(pintype "bidirectional")
		)
		(pad "W20" smd circle
			(at 8.499 7.499 90)
			(size 0.5 0.5)
			(layers "F.Cu" "F.Mask" "F.Paste")
			(net 318 "USR_LED2")
			(pinfunction "IO_L12N_T1_MRCC_14")
			(pintype "bidirectional")
		)
		(pad "W21" smd circle
			(at 9.499 7.499 90)
			(size 0.5 0.5)
			(layers "F.Cu" "F.Mask" "F.Paste")
			(net 445 "ULPI1_DIR")
			(pinfunction "IO_L7P_T1_D09_14")
			(pintype "bidirectional")
		)
		(pad "W22" smd circle
			(at 10.499 7.499 90)
			(size 0.5 0.5)
			(layers "F.Cu" "F.Mask" "F.Paste")
			(net 444 "ULPI1_NXT")
			(pinfunction "IO_L7N_T1_D10_14")
			(pintype "bidirectional")
		)
		(pad "Y1" smd circle
			(at -10.5 8.499 90)
			(size 0.5 0.5)
			(layers "F.Cu" "F.Mask" "F.Paste")
			(net 395 "RoT_CPU_RST_N_R")
			(pinfunction "IO_L5N_T0_34")
			(pintype "bidirectional")
		)
		(pad "Y2" smd circle
			(at -9.5 8.499 90)
			(size 0.5 0.5)
			(layers "F.Cu" "F.Mask" "F.Paste")
			(net 394 "SPARE1_R")
			(pinfunction "IO_L4N_T0_34")
			(pintype "bidirectional")
		)
		(pad "Y3" smd circle
			(at -8.5 8.499 90)
			(size 0.5 0.5)
			(layers "F.Cu" "F.Mask" "F.Paste")
			(net 396 "CHASI#_R")
			(pinfunction "IO_L9P_T1_DQS_34")
			(pintype "bidirectional")
		)
		(pad "Y4" smd circle
			(at -7.5 8.499 90)
			(size 0.5 0.5)
			(layers "F.Cu" "F.Mask" "F.Paste")
			(net 466 "ULPI2_DATA3")
			(pinfunction "IO_L11P_T1_SRCC_34")
			(pintype "bidirectional")
		)
		(pad "Y5" smd circle
			(at -6.5 8.499 90)
			(size 0.5 0.5)
			(layers "F.Cu" "F.Mask" "F.Paste")
			(net 1 "GND")
			(pinfunction "GND")
			(pintype "passive")
		)
		(pad "Y6" smd circle
			(at -5.5 8.499 90)
			(size 0.5 0.5)
			(layers "F.Cu" "F.Mask" "F.Paste")
			(net 90 "SGPIO1_DO")
			(pinfunction "IO_L18P_T2_34")
			(pintype "bidirectional")
		)
		(pad "Y7" smd circle
			(at -4.5 8.499 90)
			(size 0.5 0.5)
			(layers "F.Cu" "F.Mask" "F.Paste")
			(net 91 "RSVD2")
			(pinfunction "IO_L23N_T3_34")
			(pintype "bidirectional")
		)
		(pad "Y8" smd circle
			(at -3.5 8.499 90)
			(size 0.5 0.5)
			(layers "F.Cu" "F.Mask" "F.Paste")
			(net 92 "SGPIO1_DI")
			(pinfunction "IO_L23P_T3_34")
			(pintype "bidirectional")
		)
		(pad "Y9" smd circle
			(at -2.5 8.499 90)
			(size 0.5 0.5)
			(layers "F.Cu" "F.Mask" "F.Paste")
			(net 93 "SGPIO1_LD")
			(pinfunction "IO_L24N_T3_34")
			(pintype "bidirectional")
		)
		(pad "Y10" smd circle
			(at -1.5 8.499 90)
			(size 0.5 0.5)
			(layers "F.Cu" "F.Mask" "F.Paste")
			(net 2 "VCC3V3")
			(pinfunction "VCCO_13")
			(pintype "power_in")
		)
		(pad "Y11" smd circle
			(at -0.5 8.499 90)
			(size 0.5 0.5)
			(layers "F.Cu" "F.Mask" "F.Paste")
			(net 640 "unconnected-(U14A-IO_L11P_T1_SRCC_13-PadY11)")
			(pinfunction "IO_L11P_T1_SRCC_13")
			(pintype "bidirectional+no_connect")
		)
		(pad "Y12" smd circle
			(at 0.498 8.499 90)
			(size 0.5 0.5)
			(layers "F.Cu" "F.Mask" "F.Paste")
			(net 641 "unconnected-(U14A-IO_L11N_T1_SRCC_13-PadY12)")
			(pinfunction "IO_L11N_T1_SRCC_13")
			(pintype "bidirectional+no_connect")
		)
		(pad "Y13" smd circle
			(at 1.499 8.499 90)
			(size 0.5 0.5)
			(layers "F.Cu" "F.Mask" "F.Paste")
			(net 642 "unconnected-(U14A-IO_L5P_T0_13-PadY13)")
			(pinfunction "IO_L5P_T0_13")
			(pintype "bidirectional+no_connect")
		)
		(pad "Y14" smd circle
			(at 2.499 8.499 90)
			(size 0.5 0.5)
			(layers "F.Cu" "F.Mask" "F.Paste")
			(net 643 "unconnected-(U14A-IO_L6N_T0_VREF_13-PadY14)")
			(pinfunction "IO_L6N_T0_VREF_13")
			(pintype "bidirectional+no_connect")
		)
		(pad "Y15" smd circle
			(at 3.499 8.499 90)
			(size 0.5 0.5)
			(layers "F.Cu" "F.Mask" "F.Paste")
			(net 1 "GND")
			(pinfunction "GND")
			(pintype "passive")
		)
	)
)
